(kicad_pcb
	(version 20260206)
	(generator "pcbnew")
	(generator_version "10.0")
	(general
		(thickness 1.6)
		(legacy_teardrops no)
	)
	(paper "A4")
	(title_block
		(title "pdpb — Lightning_PDPB_BRD.brd")
		(comment 1 "Lightning (Wiwynn / Facebook NVMe JBOF) / footprints 917-923 of 1140")
	)
	(layers
		(0 "F.Cu" signal "TOP")
		(4 "In1.Cu" signal "L2GND")
		(6 "In2.Cu" signal "L3")
		(8 "In3.Cu" signal "L4VCC")
		(10 "In4.Cu" signal "L5VCC")
		(12 "In5.Cu" signal "L6")
		(14 "In6.Cu" signal "L7GND")
		(2 "B.Cu" signal "BOTTOM")
		(9 "F.Adhes" user "F.Adhesive")
		(11 "B.Adhes" user "B.Adhesive")
		(13 "F.Paste" user "Package Geometry/Pastemask Top")
		(15 "B.Paste" user "Package Geometry/Pastemask Bottom")
		(5 "F.SilkS" user "Ref Des/Silkscreen Top")
		(7 "B.SilkS" user "Ref Des/Silkscreen Bottom")
		(1 "F.Mask" user "Board Geometry/Soldermask Top")
		(3 "B.Mask" user "Board Geometry/Soldermask Bottom")
		(17 "Dwgs.User" user "User.Drawings")
		(19 "Cmts.User" user "User.Comments")
		(21 "Eco1.User" user "User.Eco1")
		(23 "Eco2.User" user "User.Eco2")
		(25 "Edge.Cuts" user "Board Geometry/Outline")
		(27 "Margin" user)
		(31 "F.CrtYd" user "Package Geometry/Place Bound Top")
		(29 "B.CrtYd" user "Package Geometry/Place Bound Bottom")
		(35 "F.Fab" user "Ref Des/Assembly Top")
		(33 "B.Fab" user "Ref Des/Assembly Bottom")
	)
	(footprint ""
		(layer "F.Cu")
		(at 31.8262 -112.4712 180)
		(property "Reference" "SR1117"
			(at 0 0 180)
			(layer "F.SilkS")
			(hide yes)
			(effects
				(font
					(size 1.27 1.27)
				)
			)
		)
		(property "Value" "4K7R2F-GP"
			(at 0.064008 -3.993896 180)
			(unlocked yes)
			(layer "F.Fab")
			(hide yes)
			(effects
				(font
					(size 1.016 1.016)
					(thickness 0.1524)
				)
			)
		)
		(property "Device Type" "R402H16"
			(at 0.064008 -5.517896 180)
			(unlocked yes)
			(layer "F.Fab")
			(hide yes)
			(effects
				(font
					(size 1.016 1.016)
					(thickness 0.1524)
				)
			)
		)
		(duplicate_pad_numbers_are_jumpers no)
		(fp_line
			(start 0.508 -0.9398)
			(end -0.508 -0.9398)
			(stroke
				(width 0.1524)
				(type default)
			)
			(layer "F.SilkS")
		)
		(fp_line
			(start -0.508 -0.9398)
			(end -0.508 0.9398)
			(stroke
				(width 0.1524)
				(type default)
			)
			(layer "F.SilkS")
		)
		(fp_rect
			(start -0.508 0.9398)
			(end 0.508 -0.9398)
			(stroke
				(width 0)
				(type default)
			)
			(fill no)
			(layer "F.CrtYd")
		)
		(fp_rect
			(start -0.508 0.9398)
			(end 0.508 -0.9398)
			(stroke
				(width 0)
				(type default)
			)
			(fill no)
			(layer "F.Fab")
		)
		(pad "1" smd custom
			(at 0 -0.4445 180)
			(size 0.1397 0.1397)
			(layers "F.Cu" "F.Mask" "F.Paste")
			(net "P3V3")
			(options
				(clearance outline)
				(anchor circle)
			)
			(primitives
				(gr_poly
					(pts
						(arc
							(start -0.1778 -0.2794)
							(mid -0.249642 -0.249642)
							(end -0.2794 -0.1778)
						)
						(arc
							(start -0.2794 0.1778)
							(mid -0.249642 0.249642)
							(end -0.1778 0.2794)
						)
						(arc
							(start 0.1778 0.2794)
							(mid 0.249642 0.249642)
							(end 0.2794 0.1778)
						)
						(arc
							(start 0.2794 -0.1778)
							(mid 0.249642 -0.249642)
							(end 0.1778 -0.2794)
						)
					)
					(width 0)
					(fill yes)
				)
			)
		)
		(pad "2" smd custom
			(at 0 0.4445 180)
			(size 0.1397 0.1397)
			(layers "F.Cu" "F.Mask" "F.Paste")
			(net "DUALPORTEN#13")
			(options
				(clearance outline)
				(anchor circle)
			)
			(primitives
				(gr_poly
					(pts
						(arc
							(start -0.1778 -0.2794)
							(mid -0.249642 -0.249642)
							(end -0.2794 -0.1778)
						)
						(arc
							(start -0.2794 0.1778)
							(mid -0.249642 0.249642)
							(end -0.1778 0.2794)
						)
						(arc
							(start 0.1778 0.2794)
							(mid 0.249642 0.249642)
							(end 0.2794 0.1778)
						)
						(arc
							(start 0.2794 -0.1778)
							(mid 0.249642 -0.249642)
							(end 0.1778 -0.2794)
						)
					)
					(width 0)
					(fill yes)
				)
			)
		)
	)
	(footprint ""
		(layer "F.Cu")
		(at 51.181 -14.859 180)
		(property "Reference" "R582"
			(at 0 0 180)
			(layer "F.SilkS")
			(hide yes)
			(effects
				(font
					(size 1.27 1.27)
				)
			)
		)
		(property "Value" "200KR2F-L-GP"
			(at 0.064008 -3.993896 180)
			(unlocked yes)
			(layer "F.Fab")
			(hide yes)
			(effects
				(font
					(size 1.016 1.016)
					(thickness 0.1524)
				)
			)
		)
		(property "Device Type" "R402H16"
			(at 0.064008 -5.517896 180)
			(unlocked yes)
			(layer "F.Fab")
			(hide yes)
			(effects
				(font
					(size 1.016 1.016)
					(thickness 0.1524)
				)
			)
		)
		(duplicate_pad_numbers_are_jumpers no)
		(fp_line
			(start 0.508 -0.9398)
			(end -0.508 -0.9398)
			(stroke
				(width 0.1524)
				(type default)
			)
			(layer "F.SilkS")
		)
		(fp_line
			(start -0.508 -0.9398)
			(end -0.508 0.9398)
			(stroke
				(width 0.1524)
				(type default)
			)
			(layer "F.SilkS")
		)
		(fp_rect
			(start -0.508 0.9398)
			(end 0.508 -0.9398)
			(stroke
				(width 0)
				(type default)
			)
			(fill no)
			(layer "F.CrtYd")
		)
		(fp_rect
			(start -0.508 0.9398)
			(end 0.508 -0.9398)
			(stroke
				(width 0)
				(type default)
			)
			(fill no)
			(layer "F.Fab")
		)
		(pad "1" smd custom
			(at 0 -0.4445 180)
			(size 0.1397 0.1397)
			(layers "F.Cu" "F.Mask" "F.Paste")
			(net "SW_SSD14_R")
			(options
				(clearance outline)
				(anchor circle)
			)
			(primitives
				(gr_poly
					(pts
						(arc
							(start -0.1778 -0.2794)
							(mid -0.249642 -0.249642)
							(end -0.2794 -0.1778)
						)
						(arc
							(start -0.2794 0.1778)
							(mid -0.249642 0.249642)
							(end -0.1778 0.2794)
						)
						(arc
							(start 0.1778 0.2794)
							(mid 0.249642 0.249642)
							(end 0.2794 0.1778)
						)
						(arc
							(start 0.2794 -0.1778)
							(mid 0.249642 -0.249642)
							(end 0.1778 -0.2794)
						)
					)
					(width 0)
					(fill yes)
				)
			)
		)
		(pad "2" smd custom
			(at 0 0.4445 180)
			(size 0.1397 0.1397)
			(layers "F.Cu" "F.Mask" "F.Paste")
			(net "SW_SSD14_N")
			(options
				(clearance outline)
				(anchor circle)
			)
			(primitives
				(gr_poly
					(pts
						(arc
							(start -0.1778 -0.2794)
							(mid -0.249642 -0.249642)
							(end -0.2794 -0.1778)
						)
						(arc
							(start -0.2794 0.1778)
							(mid -0.249642 0.249642)
							(end -0.1778 0.2794)
						)
						(arc
							(start 0.1778 0.2794)
							(mid 0.249642 0.249642)
							(end 0.2794 0.1778)
						)
						(arc
							(start 0.2794 -0.1778)
							(mid 0.249642 -0.249642)
							(end 0.1778 -0.2794)
						)
					)
					(width 0)
					(fill yes)
				)
			)
		)
	)
	(footprint ""
		(layer "F.Cu")
		(at 70.739 -151.638 90)
		(property "Reference" "SR970"
			(at 0 0 90)
			(layer "F.SilkS")
			(hide yes)
			(effects
				(font
					(size 1.27 1.27)
				)
			)
		)
		(property "Value" "2KR2F-3-GP"
			(at 0.064008 -3.993896 90)
			(unlocked yes)
			(layer "F.Fab")
			(hide yes)
			(effects
				(font
					(size 1.016 1.016)
					(thickness 0.1524)
				)
			)
		)
		(property "Device Type" "R402H16"
			(at 0.064008 -5.517896 90)
			(unlocked yes)
			(layer "F.Fab")
			(hide yes)
			(effects
				(font
					(size 1.016 1.016)
					(thickness 0.1524)
				)
			)
		)
		(duplicate_pad_numbers_are_jumpers no)
		(fp_line
			(start 0.508 -0.9398)
			(end -0.508 -0.9398)
			(stroke
				(width 0.1524)
				(type default)
			)
			(layer "F.SilkS")
		)
		(fp_line
			(start -0.508 -0.9398)
			(end -0.508 0.9398)
			(stroke
				(width 0.1524)
				(type default)
			)
			(layer "F.SilkS")
		)
		(fp_rect
			(start -0.508 0.9398)
			(end 0.508 -0.9398)
			(stroke
				(width 0)
				(type default)
			)
			(fill no)
			(layer "F.CrtYd")
		)
		(fp_rect
			(start -0.508 0.9398)
			(end 0.508 -0.9398)
			(stroke
				(width 0)
				(type default)
			)
			(fill no)
			(layer "F.Fab")
		)
		(pad "1" smd custom
			(at 0 -0.4445 90)
			(size 0.1397 0.1397)
			(layers "F.Cu" "F.Mask" "F.Paste")
			(net "P3V3")
			(options
				(clearance outline)
				(anchor circle)
			)
			(primitives
				(gr_poly
					(pts
						(arc
							(start -0.1778 -0.2794)
							(mid -0.249642 -0.249642)
							(end -0.2794 -0.1778)
						)
						(arc
							(start -0.2794 0.1778)
							(mid -0.249642 0.249642)
							(end -0.1778 0.2794)
						)
						(arc
							(start 0.1778 0.2794)
							(mid 0.249642 0.249642)
							(end 0.2794 0.1778)
						)
						(arc
							(start 0.2794 -0.1778)
							(mid 0.249642 -0.249642)
							(end 0.1778 -0.2794)
						)
					)
					(width 0)
					(fill yes)
				)
			)
		)
		(pad "2" smd custom
			(at 0 0.4445 90)
			(size 0.1397 0.1397)
			(layers "F.Cu" "F.Mask" "F.Paste")
			(net "SDA_DR8")
			(options
				(clearance outline)
				(anchor circle)
			)
			(primitives
				(gr_poly
					(pts
						(arc
							(start -0.1778 -0.2794)
							(mid -0.249642 -0.249642)
							(end -0.2794 -0.1778)
						)
						(arc
							(start -0.2794 0.1778)
							(mid -0.249642 0.249642)
							(end -0.1778 0.2794)
						)
						(arc
							(start 0.1778 0.2794)
							(mid 0.249642 0.249642)
							(end 0.2794 0.1778)
						)
						(arc
							(start 0.2794 -0.1778)
							(mid 0.249642 -0.249642)
							(end 0.1778 -0.2794)
						)
					)
					(width 0)
					(fill yes)
				)
			)
		)
	)
	(footprint ""
		(layer "F.Cu")
		(at 227.4316 -451.3326 90)
		(property "Reference" "R9928"
			(at 0 0 90)
			(layer "F.SilkS")
			(hide yes)
			(effects
				(font
					(size 1.27 1.27)
				)
			)
		)
		(property "Value" "4K7R2J-2-GP"
			(at 0.064008 -3.993896 90)
			(unlocked yes)
			(layer "F.Fab")
			(hide yes)
			(effects
				(font
					(size 1.016 1.016)
					(thickness 0.1524)
				)
			)
		)
		(property "Device Type" "R402H16"
			(at 0.064008 -5.517896 90)
			(unlocked yes)
			(layer "F.Fab")
			(hide yes)
			(effects
				(font
					(size 1.016 1.016)
					(thickness 0.1524)
				)
			)
		)
		(duplicate_pad_numbers_are_jumpers no)
		(fp_line
			(start 0.508 -0.9398)
			(end -0.508 -0.9398)
			(stroke
				(width 0.1524)
				(type default)
			)
			(layer "F.SilkS")
		)
		(fp_line
			(start -0.508 -0.9398)
			(end -0.508 0.9398)
			(stroke
				(width 0.1524)
				(type default)
			)
			(layer "F.SilkS")
		)
		(fp_rect
			(start -0.508 0.9398)
			(end 0.508 -0.9398)
			(stroke
				(width 0)
				(type default)
			)
			(fill no)
			(layer "F.CrtYd")
		)
		(fp_rect
			(start -0.508 0.9398)
			(end 0.508 -0.9398)
			(stroke
				(width 0)
				(type default)
			)
			(fill no)
			(layer "F.Fab")
		)
		(pad "1" smd custom
			(at 0 -0.4445 90)
			(size 0.1397 0.1397)
			(layers "F.Cu" "F.Mask" "F.Paste")
			(net "P3V3")
			(options
				(clearance outline)
				(anchor circle)
			)
			(primitives
				(gr_poly
					(pts
						(arc
							(start -0.1778 -0.2794)
							(mid -0.249642 -0.249642)
							(end -0.2794 -0.1778)
						)
						(arc
							(start -0.2794 0.1778)
							(mid -0.249642 0.249642)
							(end -0.1778 0.2794)
						)
						(arc
							(start 0.1778 0.2794)
							(mid 0.249642 0.249642)
							(end 0.2794 0.1778)
						)
						(arc
							(start 0.2794 -0.1778)
							(mid 0.249642 -0.249642)
							(end 0.1778 -0.2794)
						)
					)
					(width 0)
					(fill yes)
				)
			)
		)
		(pad "2" smd custom
			(at 0 0.4445 90)
			(size 0.1397 0.1397)
			(layers "F.Cu" "F.Mask" "F.Paste")
			(net "SSD_ACT_DR0_MOS_N")
			(options
				(clearance outline)
				(anchor circle)
			)
			(primitives
				(gr_poly
					(pts
						(arc
							(start -0.1778 -0.2794)
							(mid -0.249642 -0.249642)
							(end -0.2794 -0.1778)
						)
						(arc
							(start -0.2794 0.1778)
							(mid -0.249642 0.249642)
							(end -0.1778 0.2794)
						)
						(arc
							(start 0.1778 0.2794)
							(mid 0.249642 0.249642)
							(end 0.2794 0.1778)
						)
						(arc
							(start 0.2794 -0.1778)
							(mid 0.249642 -0.249642)
							(end 0.1778 -0.2794)
						)
					)
					(width 0)
					(fill yes)
				)
			)
		)
	)
	(footprint ""
		(layer "F.Cu")
		(at 83.185 -154.686 90)
		(property "Reference" "PR9059"
			(at 0 0 90)
			(layer "F.SilkS")
			(hide yes)
			(effects
				(font
					(size 1.27 1.27)
				)
			)
		)
		(property "Value" "0R2J-2-GP"
			(at 0.064008 -3.993896 90)
			(unlocked yes)
			(layer "F.Fab")
			(hide yes)
			(effects
				(font
					(size 1.016 1.016)
					(thickness 0.1524)
				)
			)
		)
		(property "Device Type" "R402H16"
			(at 0.064008 -5.517896 90)
			(unlocked yes)
			(layer "F.Fab")
			(hide yes)
			(effects
				(font
					(size 1.016 1.016)
					(thickness 0.1524)
				)
			)
		)
		(duplicate_pad_numbers_are_jumpers no)
		(fp_line
			(start 0.508 -0.9398)
			(end -0.508 -0.9398)
			(stroke
				(width 0.1524)
				(type default)
			)
			(layer "F.SilkS")
		)
		(fp_line
			(start -0.508 -0.9398)
			(end -0.508 0.9398)
			(stroke
				(width 0.1524)
				(type default)
			)
			(layer "F.SilkS")
		)
		(fp_rect
			(start -0.508 0.9398)
			(end 0.508 -0.9398)
			(stroke
				(width 0)
				(type default)
			)
			(fill no)
			(layer "F.CrtYd")
		)
		(fp_rect
			(start -0.508 0.9398)
			(end 0.508 -0.9398)
			(stroke
				(width 0)
				(type default)
			)
			(fill no)
			(layer "F.Fab")
		)
		(pad "1" smd custom
			(at 0 -0.4445 90)
			(size 0.1397 0.1397)
			(layers "F.Cu" "F.Mask" "F.Paste")
			(net "I2C_MUX_RESET_PEB")
			(options
				(clearance outline)
				(anchor circle)
			)
			(primitives
				(gr_poly
					(pts
						(arc
							(start -0.1778 -0.2794)
							(mid -0.249642 -0.249642)
							(end -0.2794 -0.1778)
						)
						(arc
							(start -0.2794 0.1778)
							(mid -0.249642 0.249642)
							(end -0.1778 0.2794)
						)
						(arc
							(start 0.1778 0.2794)
							(mid 0.249642 0.249642)
							(end 0.2794 0.1778)
						)
						(arc
							(start 0.2794 -0.1778)
							(mid 0.249642 -0.249642)
							(end 0.1778 -0.2794)
						)
					)
					(width 0)
					(fill yes)
				)
			)
		)
		(pad "2" smd custom
			(at 0 0.4445 90)
			(size 0.1397 0.1397)
			(layers "F.Cu" "F.Mask" "F.Paste")
			(net "I2C_MUX_RESET")
			(options
				(clearance outline)
				(anchor circle)
			)
			(primitives
				(gr_poly
					(pts
						(arc
							(start -0.1778 -0.2794)
							(mid -0.249642 -0.249642)
							(end -0.2794 -0.1778)
						)
						(arc
							(start -0.2794 0.1778)
							(mid -0.249642 0.249642)
							(end -0.1778 0.2794)
						)
						(arc
							(start 0.1778 0.2794)
							(mid 0.249642 0.249642)
							(end 0.2794 0.1778)
						)
						(arc
							(start 0.2794 -0.1778)
							(mid 0.249642 -0.249642)
							(end 0.1778 -0.2794)
						)
					)
					(width 0)
					(fill yes)
				)
			)
		)
	)
	(footprint ""
		(layer "F.Cu")
		(at 49.276 -42.418 -90)
		(property "Reference" "R9493"
			(at 0 0 270)
			(layer "F.SilkS")
			(hide yes)
			(effects
				(font
					(size 1.27 1.27)
				)
			)
		)
		(property "Value" "330R2F-GP"
			(at 0.064008 -3.993896 270)
			(unlocked yes)
			(layer "F.Fab")
			(hide yes)
			(effects
				(font
					(size 1.016 1.016)
					(thickness 0.1524)
				)
			)
		)
		(property "Device Type" "R402H16"
			(at 0.064008 -5.517896 270)
			(unlocked yes)
			(layer "F.Fab")
			(hide yes)
			(effects
				(font
					(size 1.016 1.016)
					(thickness 0.1524)
				)
			)
		)
		(duplicate_pad_numbers_are_jumpers no)
		(fp_line
			(start -0.508 -0.9398)
			(end -0.508 0.9398)
			(stroke
				(width 0.1524)
				(type default)
			)
			(layer "F.SilkS")
		)
		(fp_line
			(start 0.508 -0.9398)
			(end -0.508 -0.9398)
			(stroke
				(width 0.1524)
				(type default)
			)
			(layer "F.SilkS")
		)
		(fp_rect
			(start -0.508 0.9398)
			(end 0.508 -0.9398)
			(stroke
				(width 0)
				(type default)
			)
			(fill no)
			(layer "F.CrtYd")
		)
		(fp_rect
			(start -0.508 0.9398)
			(end 0.508 -0.9398)
			(stroke
				(width 0)
				(type default)
			)
			(fill no)
			(layer "F.Fab")
		)
		(pad "1" smd custom
			(at 0 -0.4445 270)
			(size 0.1397 0.1397)
			(layers "F.Cu" "F.Mask" "F.Paste")
			(net "P3V3")
			(options
				(clearance outline)
				(anchor circle)
			)
			(primitives
				(gr_poly
					(pts
						(arc
							(start -0.1778 -0.2794)
							(mid -0.249642 -0.249642)
							(end -0.2794 -0.1778)
						)
						(arc
							(start -0.2794 0.1778)
							(mid -0.249642 0.249642)
							(end -0.1778 0.2794)
						)
						(arc
							(start 0.1778 0.2794)
							(mid 0.249642 0.249642)
							(end 0.2794 0.1778)
						)
						(arc
							(start 0.2794 -0.1778)
							(mid 0.249642 -0.249642)
							(end 0.1778 -0.2794)
						)
					)
					(width 0)
					(fill yes)
				)
			)
		)
		(pad "2" smd custom
			(at 0 0.4445 270)
			(size 0.1397 0.1397)
			(layers "F.Cu" "F.Mask" "F.Paste")
			(net "DRV_ATTN_9")
			(options
				(clearance outline)
				(anchor circle)
			)
			(primitives
				(gr_poly
					(pts
						(arc
							(start -0.1778 -0.2794)
							(mid -0.249642 -0.249642)
							(end -0.2794 -0.1778)
						)
						(arc
							(start -0.2794 0.1778)
							(mid -0.249642 0.249642)
							(end -0.1778 0.2794)
						)
						(arc
							(start 0.1778 0.2794)
							(mid 0.249642 0.249642)
							(end 0.2794 0.1778)
						)
						(arc
							(start 0.2794 -0.1778)
							(mid 0.249642 -0.249642)
							(end 0.1778 -0.2794)
						)
					)
					(width 0)
					(fill yes)
				)
			)
		)
	)
	(footprint ""
		(layer "F.Cu")
		(at 36.576 -165.354 180)
		(property "Reference" "PC1219"
			(at 0 0 180)
			(layer "F.SilkS")
			(hide yes)
			(effects
				(font
					(size 1.27 1.27)
				)
			)
		)
		(property "Value" "SCD1U25V3KX-GP"
			(at 0 -2.8194 180)
			(unlocked yes)
			(layer "F.Fab")
			(hide yes)
			(effects
				(font
					(size 1.016 1.016)
					(thickness 0.1524)
				)
			)
		)
		(property "Device Type" "C603H36"
			(at 0 -4.3434 180)
			(unlocked yes)
			(layer "F.Fab")
			(hide yes)
			(effects
				(font
					(size 1.016 1.016)
					(thickness 0.1524)
				)
			)
		)
		(duplicate_pad_numbers_are_jumpers no)
		(fp_line
			(start 0.508 0)
			(end -0.508 0)
			(stroke
				(width 0.2032)
				(type default)
			)
			(layer "F.SilkS")
		)
		(fp_rect
			(start -0.5842 1.3335)
			(end 0.5842 -1.3335)
			(stroke
				(width 0)
				(type default)
			)
			(fill no)
			(layer "F.CrtYd")
		)
		(fp_rect
			(start -0.5842 1.3335)
			(end 0.5842 -1.3335)
			(stroke
				(width 0)
				(type default)
			)
			(fill no)
			(layer "F.Fab")
		)
		(pad "1" smd custom
			(at 0 -0.762 180)
			(size 0.2159 0.2159)
			(layers "F.Cu" "F.Mask" "F.Paste")
			(net "P3V3")
			(options
				(clearance outline)
				(anchor circle)
			)
			(primitives
				(gr_poly
					(pts
						(arc
							(start -0.3302 -0.4318)
							(mid -0.402042 -0.402042)
							(end -0.4318 -0.3302)
						)
						(arc
							(start -0.4318 0.3302)
							(mid -0.402042 0.402042)
							(end -0.3302 0.4318)
						)
						(arc
							(start 0.3302 0.4318)
							(mid 0.402042 0.402042)
							(end 0.4318 0.3302)
						)
						(arc
							(start 0.4318 -0.3302)
							(mid 0.402042 -0.402042)
							(end 0.3302 -0.4318)
						)
					)
					(width 0)
					(fill yes)
				)
			)
		)
		(pad "2" smd custom
			(at 0 0.762 180)
			(size 0.2159 0.2159)
			(layers "F.Cu" "F.Mask" "F.Paste")
			(net "GND")
			(options
				(clearance outline)
				(anchor circle)
			)
			(primitives
				(gr_poly
					(pts
						(arc
							(start -0.3302 -0.4318)
							(mid -0.402042 -0.402042)
							(end -0.4318 -0.3302)
						)
						(arc
							(start -0.4318 0.3302)
							(mid -0.402042 0.402042)
							(end -0.3302 0.4318)
						)
						(arc
							(start 0.3302 0.4318)
							(mid 0.402042 0.402042)
							(end 0.4318 0.3302)
						)
						(arc
							(start 0.4318 -0.3302)
							(mid 0.402042 -0.402042)
							(end 0.3302 -0.4318)
						)
					)
					(width 0)
					(fill yes)
				)
			)
		)
	)
)
